# T6G (Grand Teton) — schematic netlist excerpt (pin names and nets, part order shuffled) for the footprints in the layout excerpt that follows; sources: Cadence DE-HDL packaged netlist, KiCad conversion of 04192023_DAF0TMB3IC0_F0TG_MB_C_brd_V02_OCP.brd

R6773  Q_RES  4.7K 5% CHIP  pkg 0201LF  page 184 : A = RT_SMB_MUX_ADDR2 ; B = GND
PC279  Q_CAPP  220UF 4V 20% SPCAP  pkg SMLF  page 211 : A = PVDDCR_CPU0_P1 ; B = GND
R295  Q_RES  1K 1% CHIP  pkg 0402LF  page 90 : A = PWRGD_CHE_CPU0_DIMM ; B = PWRGD_CHAF_CPU0

(kicad_pcb
	(version 20260206)
	(generator "pcbnew")
	(generator_version "10.0")
	(general
		(thickness 1.6)
		(legacy_teardrops no)
	)
	(paper "A4")
	(title_block
		(title "04192023_DAF0TMB3IC0_F0TG_MB_C_brd_V02_OCP.brd")
		(comment 1 "Grand Teton / footprints 4996-4998 of 8354")
	)
	(layers
		(0 "F.Cu" signal "TOP")
		(4 "In1.Cu" signal "GND")
		(6 "In2.Cu" signal "IN1")
		(8 "In3.Cu" signal "GND1")
		(10 "In4.Cu" signal "IN2")
		(12 "In5.Cu" signal "GND2")
		(14 "In6.Cu" signal "IN3")
		(16 "In7.Cu" signal "GND3")
		(18 "In8.Cu" signal "VCC")
		(20 "In9.Cu" signal "VCC1")
		(22 "In10.Cu" signal "GND4")
		(24 "In11.Cu" signal "IN4")
		(26 "In12.Cu" signal "GND5")
		(28 "In13.Cu" signal "IN5")
		(30 "In14.Cu" signal "GND6")
		(32 "In15.Cu" signal "IN6")
		(34 "In16.Cu" signal "GND7")
		(2 "B.Cu" signal "BOTTOM")
		(9 "F.Adhes" user "F.Adhesive")
		(11 "B.Adhes" user "B.Adhesive")
		(13 "F.Paste" user "Package Geometry/Pastemask Top")
		(15 "B.Paste" user "Package Geometry/Pastemask Bottom")
		(5 "F.SilkS" user "Ref Des/Silkscreen Top")
		(7 "B.SilkS" user "Ref Des/Silkscreen Bottom")
		(1 "F.Mask" user "Board Geometry/Soldermask Top")
		(3 "B.Mask" user "Board Geometry/Soldermask Bottom")
		(17 "Dwgs.User" user "User.Drawings")
		(19 "Cmts.User" user "User.Comments")
		(21 "Eco1.User" user "User.Eco1")
		(23 "Eco2.User" user "User.Eco2")
		(25 "Edge.Cuts" user "Board Geometry/Outline")
		(27 "Margin" user)
		(31 "F.CrtYd" user "Package Geometry/Place Bound Top")
		(29 "B.CrtYd" user "Package Geometry/Place Bound Bottom")
		(35 "F.Fab" user "Ref Des/Assembly Top")
		(33 "B.Fab" user "Ref Des/Assembly Bottom")
	)
	(footprint ""
		(layer "B.Cu")
		(at 73.248774 -184.343548 90)
		(property "Reference" "PC279"
			(at 5.811012 0.851916 270)
			(unlocked yes)
			(layer "B.SilkS")
			(effects
				(font
					(size 0.7874 0.5842)
					(thickness 0.1524)
				)
				(justify left mirror)
			)
		)
		(property "Value" ""
			(at 0 0 90)
			(layer "B.Fab")
			(effects
				(font
					(size 1.27 1.27)
				)
				(justify mirror)
			)
		)
		(duplicate_pad_numbers_are_jumpers no)
		(fp_line
			(start 4.533392 -2.249932)
			(end -4.533392 -2.249932)
			(stroke
				(width 0.1524)
				(type default)
			)
			(layer "B.SilkS")
		)
		(fp_line
			(start -4.533392 -2.249932)
			(end -4.533392 2.249932)
			(stroke
				(width 0.1524)
				(type default)
			)
			(layer "B.SilkS")
		)
		(fp_line
			(start 4.533392 2.249932)
			(end 4.533392 -2.249932)
			(stroke
				(width 0.1524)
				(type default)
			)
			(layer "B.SilkS")
		)
		(fp_line
			(start -4.533392 2.249932)
			(end 4.533392 2.249932)
			(stroke
				(width 0.1524)
				(type default)
			)
			(layer "B.SilkS")
		)
		(fp_rect
			(start 4.533392 -2.326132)
			(end 5.39242 2.326132)
			(stroke
				(width 0)
				(type default)
			)
			(fill yes)
			(layer "B.SilkS")
		)
		(fp_line
			(start 3.750056 -2.249932)
			(end -3.750056 -2.249932)
			(stroke
				(width 0.1)
				(type default)
			)
			(layer "B.Fab")
		)
		(fp_line
			(start -3.750056 -2.249932)
			(end -3.750056 2.249932)
			(stroke
				(width 0.1)
				(type default)
			)
			(layer "B.Fab")
		)
		(fp_line
			(start 3.750056 2.249932)
			(end 3.750056 -2.249932)
			(stroke
				(width 0.1)
				(type default)
			)
			(layer "B.Fab")
		)
		(fp_line
			(start -3.750056 2.249932)
			(end 3.750056 2.249932)
			(stroke
				(width 0.1)
				(type default)
			)
			(layer "B.Fab")
		)
		(fp_text user "+"
			(at 6.322314 0.786384 0)
			(unlocked yes)
			(layer "B.SilkS")
			(effects
				(font
					(size 1.905 1.4224)
					(thickness 0.1524)
				)
				(justify left mirror)
			)
		)
		(fp_text user "-"
			(at -4.83997 0.996696 90)
			(unlocked yes)
			(layer "B.SilkS")
			(effects
				(font
					(size 1.905 1.4224)
					(thickness 0.1524)
				)
				(justify left mirror)
			)
		)
		(fp_text user "-"
			(at -4.8514 -0.14605 90)
			(unlocked yes)
			(layer "B.Fab")
			(effects
				(font
					(size 1.905 1.4224)
					(thickness 0.1524)
				)
				(justify left mirror)
			)
		)
		(fp_text user "+"
			(at 6.322314 0.786384 0)
			(unlocked yes)
			(layer "B.Fab")
			(effects
				(font
					(size 1.905 1.4224)
					(thickness 0.1524)
				)
				(justify left mirror)
			)
		)
		(pad "1" smd rect
			(at 3.199892 0 270)
			(size 2.413 2.8194)
			(layers "B.Cu" "B.Mask" "B.Paste")
			(net "PVDDCR_CPU0_P1")
		)
		(pad "2" smd rect
			(at -3.199892 0 270)
			(size 2.413 2.8194)
			(layers "B.Cu" "B.Mask" "B.Paste")
			(net "GND")
		)
	)
	(footprint ""
		(layer "B.Cu")
		(at 233.807 -332.74 180)
		(property "Reference" "R6773"
			(at 0 0 0)
			(layer "B.SilkS")
			(hide yes)
			(effects
				(font
					(size 1.27 1.27)
				)
				(justify mirror)
			)
		)
		(property "Value" ""
			(at 0 0 0)
			(layer "B.Fab")
			(effects
				(font
					(size 1.27 1.27)
				)
				(justify mirror)
			)
		)
		(duplicate_pad_numbers_are_jumpers no)
		(fp_line
			(start 0.32512 0.175006)
			(end 0.32512 -0.175006)
			(stroke
				(width 0.1)
				(type default)
			)
			(layer "B.Fab")
		)
		(fp_line
			(start 0.32512 -0.175006)
			(end -0.32512 -0.175006)
			(stroke
				(width 0.1)
				(type default)
			)
			(layer "B.Fab")
		)
		(fp_line
			(start -0.32512 0.175006)
			(end 0.32512 0.175006)
			(stroke
				(width 0.1)
				(type default)
			)
			(layer "B.Fab")
		)
		(fp_line
			(start -0.32512 -0.175006)
			(end -0.32512 0.175006)
			(stroke
				(width 0.1)
				(type default)
			)
			(layer "B.Fab")
		)
		(pad "1" smd rect
			(at 0.2667 0)
			(size 0.3048 0.381)
			(layers "B.Cu" "B.Mask" "B.Paste")
			(net "RT_SMB_MUX_ADDR2")
		)
		(pad "2" smd rect
			(at -0.2667 0 180)
			(size 0.3048 0.381)
			(layers "B.Cu" "B.Mask" "B.Paste")
			(net "GND")
		)
	)
	(footprint ""
		(layer "B.Cu")
		(at 273.253454 -190.94831 180)
		(property "Reference" "R295"
			(at 0 0 0)
			(layer "B.SilkS")
			(hide yes)
			(effects
				(font
					(size 1.27 1.27)
				)
				(justify mirror)
			)
		)
		(property "Value" ""
			(at 0 0 0)
			(layer "B.Fab")
			(effects
				(font
					(size 1.27 1.27)
				)
				(justify mirror)
			)
		)
		(duplicate_pad_numbers_are_jumpers no)
		(fp_line
			(start 0.7874 0.4064)
			(end 0.7874 -0.4064)
			(stroke
				(width 0.1524)
				(type default)
			)
			(layer "B.SilkS")
		)
		(fp_line
			(start 0.7874 -0.4064)
			(end -0.7874 -0.4064)
			(stroke
				(width 0.1524)
				(type default)
			)
			(layer "B.SilkS")
		)
		(fp_line
			(start -0.7874 0.4064)
			(end 0.7874 0.4064)
			(stroke
				(width 0.1524)
				(type default)
			)
			(layer "B.SilkS")
		)
		(fp_line
			(start -0.7874 -0.4064)
			(end -0.7874 0.4064)
			(stroke
				(width 0.1524)
				(type default)
			)
			(layer "B.SilkS")
		)
		(fp_line
			(start 0.67945 0.3048)
			(end 0.67945 -0.305054)
			(stroke
				(width 0.1)
				(type default)
			)
			(layer "B.Fab")
		)
		(fp_line
			(start 0.67945 -0.305054)
			(end 0.12065 -0.305054)
			(stroke
				(width 0.1)
				(type default)
			)
			(layer "B.Fab")
		)
		(fp_line
			(start 0.12065 0.3048)
			(end 0.67945 0.3048)
			(stroke
				(width 0.1)
				(type default)
			)
			(layer "B.Fab")
		)
		(fp_line
			(start 0.12065 0.2794)
			(end 0.12065 0.3048)
			(stroke
				(width 0.1)
				(type default)
			)
			(layer "B.Fab")
		)
		(fp_line
			(start 0.12065 -0.2794)
			(end -0.12065 -0.2794)
			(stroke
				(width 0.1)
				(type default)
			)
			(layer "B.Fab")
		)
		(fp_line
			(start 0.12065 -0.305054)
			(end 0.12065 -0.2794)
			(stroke
				(width 0.1)
				(type default)
			)
			(layer "B.Fab")
		)
		(fp_line
			(start -0.120396 0.3048)
			(end -0.120396 0.2794)
			(stroke
				(width 0.1)
				(type default)
			)
			(layer "B.Fab")
		)
		(fp_line
			(start -0.120396 0.2794)
			(end 0.12065 0.2794)
			(stroke
				(width 0.1)
				(type default)
			)
			(layer "B.Fab")
		)
		(fp_line
			(start -0.12065 -0.2794)
			(end -0.12065 -0.3048)
			(stroke
				(width 0.1)
				(type default)
			)
			(layer "B.Fab")
		)
		(fp_line
			(start -0.12065 -0.3048)
			(end -0.67945 -0.3048)
			(stroke
				(width 0.1)
				(type default)
			)
			(layer "B.Fab")
		)
		(fp_line
			(start -0.67945 0.3048)
			(end -0.120396 0.3048)
			(stroke
				(width 0.1)
				(type default)
			)
			(layer "B.Fab")
		)
		(fp_line
			(start -0.67945 -0.3048)
			(end -0.67945 0.3048)
			(stroke
				(width 0.1)
				(type default)
			)
			(layer "B.Fab")
		)
		(pad "1" smd circle
			(at 0.40005 0)
			(size 0 0)
			(layers "B.Cu" "B.Mask" "B.Paste")
			(net "PWRGD_CHE_CPU0_DIMM")
		)
		(pad "2" smd circle
			(at -0.40005 0)
			(size 0 0)
			(layers "B.Cu" "B.Mask" "B.Paste")
			(net "PWRGD_CHAF_CPU0")
		)
	)
)
